# BASEBOARD_FAB2 (Tioga Pass) — schematic parts with pin connectivity, parts 2989–3136 of 4751; source: Cadence DE-HDL packaged netlist (pstxprt.dat, pstxnet.dat, pstchip.dat)

R2T63  RES  0.0 5% EMPTY  pkg 0402  page 93 : 1 = FM_CPU_ERR1_LVT3_N ; 2 = FM_CPU_ERR1_PCH_N
R2T64  RES  0.0 5% CHIP  pkg 0402  page 93 : 1 = FM_CPU_ERR1_LVT3_N ; 2 = FM_CPU_ERR1_LVT3_BMC_N
R2T65  RES  0.0 5% CHIP  pkg 0402  page 93 : 1 = FM_CPU_ERR0_LVT3_R_N ; 2 = FM_CPU_ERR0_LVT3_K_N
R2T66  RES  0.0 5% CHIP  pkg 0402  page 93 : 1 = FM_CPU_ERR1_LVT3_R_N ; 2 = FM_CPU_ERR1_LVT3_K_N
R2T67  RES  0.0 5% CHIP  pkg 0402  page 93 : 1 = FM_CPU0_PROCHOT_LVT3_R_N ; 2 = FM_CPU0_PROCHOT_LVT3_K_N
R2T68  RES  0.0 5% CHIP  pkg 0402  page 93 : 1 = H_CPU1_PROCHOT_G_N ; 2 = H_CPU1_PROCHOT_G_R_N
R2T69  RES  0.0 5% EMPTY  pkg 0402  page 93 : 1 = H_CPU1_PROCHOT_G_N ; 2 = H_CPU1_PROCHOT_G_PCH_N
R2T71  RES  0.0 5% EMPTY  pkg 0402  page 93 : 1 = FM_CPU0_PROCHOT_LVT3_K_N ; 2 = H_CPU0_PROCHOT_G_PCH_N
R2T72  RES  150.0 1% CHIP  pkg 0402  page 93 : 1 = PVCCIO_CPU0 ; 2 = H_CPU0_PROCHOT_G_N
R2T73  RES  150.0 1% CHIP  pkg 0402  page 93 : 1 = PVCCIO_CPU1 ; 2 = H_CPU1_PROCHOT_G_N
R2U1  RES  20.0 1% CHIP  pkg 0402  page 159 : 1 = SMB_BMC_PMBUS_STBY_LVC3_SCL_R ; 2 = SMB_BMC_PMBUS_STBY_LVC3_SCL
R2U2  RES  4.75K 1% CHIP  pkg 0402  page 156 : 1 = P3V3_STBY ; 2 = RST_PCH_SYSRST_BTN_OUT_N
R2U3  RES  665 1.0% CHIP  pkg 0402  page 138 : 1 = P3V3_STBY ; 2 = SMB_LAN_STBY_LVC3_SCL
R2U4  RES  4.75K 1% CHIP  pkg 0402  page 157 : 1 = P3V3_STBY ; 2 = FM_CPLD_BMC_PWRDN_N
R2U5  RES  2.26K 1.0% CHIP  pkg 0402  page 159 : 1 = P3V3_STBY ; 2 = SMB_OCP_FRU_STBY_LVC3_SCL_R
R2U6  RES  20.0 1% CHIP  pkg 0402  page 138 : 1 = SMB_LAN_STBY_LVC3_SCL_R1 ; 2 = SMB_LAN_STBY_LVC3_SCL
R2U7  RES  20.0 1% CHIP  pkg 0402  page 159 : 1 = SMB_OCP_FRU_STBY_LVC3_SCL_R ; 2 = SMB_OCP_FRU_STBY_LVC3_SCL
R2U8  RES  20.0 1% EMPTY  pkg 0402  page 138 : 1 = SMB_LAN_STBY_LVC3_SCL ; 2 = SMB_OCP_FRU_STBY_LVC3_SCL
R2U9  RES  20.0 1% CHIP  pkg 0402  page 138 : 1 = SMB_LAN_STBY_LVC3_SDA_R1 ; 2 = SMB_LAN_STBY_LVC3_SDA
R2U10  RES  20.0 1% CHIP  pkg 0402  page 159 : 1 = SMB_OCP_FRU_STBY_LVC3_SDA_R ; 2 = SMB_OCP_FRU_STBY_LVC3_SDA
R2U11  RES  665 1.0% CHIP  pkg 0402  page 138 : 1 = P3V3_STBY ; 2 = SMB_LAN_STBY_LVC3_SDA
R2U12  RES  20.0 1% EMPTY  pkg 0402  page 138 : 1 = SMB_LAN_STBY_LVC3_SDA ; 2 = SMB_OCP_FRU_STBY_LVC3_SDA
R2U13  RES  2.26K 1.0% CHIP  pkg 0402  page 159 : 1 = P3V3_STBY ; 2 = SMB_OCP_FRU_STBY_LVC3_SDA_R
R2U14  RES  0.0 5% CHIP  pkg 0402  page 107 : 1 = P3E_CPU0_PE1_SS_RXP<0> ; 2 = P3E_CPU0_PE1_SS_R_RXP<0>
R2U15  RES  0.0 5% CHIP  pkg 0402  page 107 : 1 = P3E_CPU0_PE1_SS_RXN<0> ; 2 = P3E_CPU0_PE1_SS_R_RXN<0>
R2U16  RES  0.0 5% CHIP  pkg 0402  page 107 : 1 = P3E_CPU0_PE1_SS_RXP<1> ; 2 = P3E_CPU0_PE1_SS_R_RXP<1>
R2U17  RES  0.0 5% CHIP  pkg 0402  page 107 : 1 = P3E_CPU0_PE1_SS_RXN<1> ; 2 = P3E_CPU0_PE1_SS_R_RXN<1>
R2U18  RES  0.0 5% CHIP  pkg 0402  page 107 : 1 = P3E_CPU0_PE1_SS_RXP<2> ; 2 = P3E_CPU0_PE1_SS_R_RXP<2>
R2U19  RES  0.0 5% CHIP  pkg 0402  page 107 : 1 = P3E_CPU0_PE1_SS_RXN<2> ; 2 = P3E_CPU0_PE1_SS_R_RXN<2>
R2U20  RES  0.0 5% CHIP  pkg 0402  page 107 : 1 = P3E_CPU0_PE1_SS_RXP<3> ; 2 = P3E_CPU0_PE1_SS_R_RXP<3>
R2U21  RES  0.0 5% CHIP  pkg 0402  page 107 : 1 = P3E_CPU0_PE1_SS_RXN<3> ; 2 = P3E_CPU0_PE1_SS_R_RXN<3>
R2U22  RES  0.0 5% CHIP  pkg 0402  page 107 : 1 = P3E_CPU0_PE1_SS_RXP<4> ; 2 = P3E_CPU0_PE1_SS_R_RXP<4>
R2U23  RES  0.0 5% CHIP  pkg 0402  page 107 : 1 = P3E_CPU0_PE1_SS_RXN<4> ; 2 = P3E_CPU0_PE1_SS_R_RXN<4>
R2U24  RES  0.0 5% CHIP  pkg 0402  page 107 : 1 = P3E_CPU0_PE1_SS_RXP<5> ; 2 = P3E_CPU0_PE1_SS_R_RXP<5>
R2U25  RES  0.0 5% CHIP  pkg 0402  page 107 : 1 = P3E_CPU0_PE1_SS_RXN<5> ; 2 = P3E_CPU0_PE1_SS_R_RXN<5>
R2U26  RES  0.0 5% CHIP  pkg 0402  page 107 : 1 = P3E_CPU0_PE1_SS_RXP<6> ; 2 = P3E_CPU0_PE1_SS_R_RXP<6>
R2U27  RES  0.0 5% CHIP  pkg 0402  page 107 : 1 = P3E_CPU0_PE1_SS_RXN<6> ; 2 = P3E_CPU0_PE1_SS_R_RXN<6>
R2U28  RES  0.0 5% CHIP  pkg 0402  page 107 : 1 = P3E_CPU0_PE1_SS_RXP<7> ; 2 = P3E_CPU0_PE1_SS_R_RXP<7>
R2U29  RES  0.0 5% CHIP  pkg 0402  page 107 : 1 = P3E_CPU0_PE1_SS_RXN<7> ; 2 = P3E_CPU0_PE1_SS_R_RXN<7>
R2U30  RES  4.75K 1% EMPTY  pkg 0402  page 125 : 1 = P3V3_STBY ; 2 = FM_UV_ADR_TRIGGER_EN
R2U31  RES  20.0 1% CHIP  pkg 0402  page 108 : 1 = SMB_SLOTX24_BMC_STBY_LVC3_SDA ; 2 = SMB_SLOTX24_STBY_LVC3_SDA_R2
R2U32  RES  20.0 1% CHIP  pkg 0402  page 108 : 1 = SMB_SLOTX24_BMC_STBY_LVC3_SCL ; 2 = SMB_SLOTX24_STBY_LVC3_SCL_R2
R2U33  RES  20.0 1% CHIP  pkg 0402  page 159 : 1 = SMB_HOST_STBY_LVC3_SDA_R ; 2 = SMB_HOST_STBY_LVC3_SDA
R2U34  RES  20.0 1% CHIP  pkg 0402  page 159 : 1 = SMB_HOST_STBY_LVC3_SCL_R ; 2 = SMB_HOST_STBY_LVC3_SCL
R2U35  RES  20.0 1% EMPTY  pkg 0402  page 108 : 1 = SMB_SLOTX24_PCH_STBY_LVC3_SDA ; 2 = SMB_SLOTX24_STBY_LVC3_SDA_R2
R2U36  RES  20.0 1% EMPTY  pkg 0402  page 108 : 1 = SMB_SLOTX24_PCH_STBY_LVC3_SCL ; 2 = SMB_SLOTX24_STBY_LVC3_SCL_R2
R2U37  RES  0.0 5% CHIP  pkg 0402  page 108 : 1 = RST_PCIE_RISER1_PERST_N ; 2 = RST_PCIE_RISER1_PERST_R_N
R2U38  RES  665 1.0% CHIP  pkg 0402  page 167 : 1 = P3V3_STBY ; 2 = SMB_SENSOR_STBY_LVC3_SCL
R2U39  RES  665 1.0% CHIP  pkg 0402  page 167 : 1 = P3V3_STBY ; 2 = SMB_SENSOR_STBY_LVC3_SDA
R2U40  RES  150.0 1% CHIP  pkg 0402  page 152 : 1 = PVCCIO_CPU0 ; 2 = H_CPU0_MEMABC_MEMHOT_G_N
R2U41  RES  150.0 1% CHIP  pkg 0402  page 152 : 1 = PVCCIO_CPU0 ; 2 = H_CPU0_MEMDEF_MEMHOT_G_N
R2U42  RES  221 1.0% CHIP  pkg 0402  page 161 : 1 = FAN_PWM_OUT_SYS0_BUF ; 2 = FAN_PWM_OUT_SYS0_R
R2U43  RES  1.00K 1% CHIP  pkg 0402  page 196 : 1 = P3V_BAT_SOURCE ; 2 = A_P3V_BAT_R
R2U44  RES  221 1.0% CHIP  pkg 0402  page 161 : 1 = FAN_PWM_OUT_SYS1_BUF ; 2 = FAN_PWM_OUT_SYS1_R
R2U45  RES  0.0 5% EMPTY  pkg 0402  page 152 : 1 = H_CPU1_MEMKLM_MEMHOT_LVT3_N ; 2 = H_CPU1_MEMKLM_MEMHOT_PCH_N
R2U46  RES  0.0 5% CHIP  pkg 0402  page 152 : 1 = H_CPU1_MEMKLM_MEMHOT_LVT3_N ; 2 = H_CPU1_MEMKLM_MEMHOT_LVT3_BMC_N
R2U47  RES  0.0 5% CHIP  pkg 0402  page 152 : 1 = H_CPU0_MEMABC_MEMHOT_LVT3_N ; 2 = H_CPU0_MEMABC_MEMHOT_LVT3_BMC_N
R2U48  RES  4.75K 1% CHIP  pkg 0402  page 119 : 1 = P3V3_STBY ; 2 = FM_SLT_CFG2_R
R2U49  RES  0.0 5% EMPTY  pkg 0402  page 152 : 1 = H_CPU0_MEMABC_MEMHOT_G_PCH_N ; 2 = H_CPU0_MEMABC_MEMHOT_LVT3_K_N
R2U50  RES  0.0 5% CHIP  pkg 0402  page 119 : 1 = FM_SLT_CFG2_R ; 2 = FM_PWRBRK_SLOT_N
R2U51  RES  0.0 5% EMPTY  pkg 0402  page 152 : 1 = H_CPU0_MEMABC_MEMHOT_G_PCH_N ; 2 = H_CPU0_MEMABC_MEMHOT_G_N
R2W1  RES  10.0K 1% CHIP  pkg 0402  page 187 : 1 = P3V3_STBY ; 2 = FM_MEZZB_PRSNT1_N
R2W2  RES  49.9 1% EMPTY  pkg 0402  page 93 : 1 = PVCCIO_CPU0 ; 2 = P0V7_GTL2104_5_VREF
R2W3  RES  0.0 5% CHIP  pkg 0402  page 119 : 1 = FM_PMBUS_ALERT_BUF_EN_R_N ; 2 = FM_PMBUS_ALERT_BUF_EN_N
R2W4  RES  0.0 5% CHIP  pkg 0402  page 119 : 1 = FM_PMBUS_ALERT_BUF_EN_N ; 2 = FM_PMBUS_ALERT_BUF_EN_R2_N
R2W5  RES  0.0 5% CHIP  pkg 0402  page 145 : 1 = FM_PMBUS_ALERT_BUF_EN_R3_N ; 2 = FM_PMBUS_ALERT_BUF_EN_N
R3B1  RES  221 1.0% CHIP  pkg 0402  page 55 : 1 = SVID_ALERT0_CPU1_N ; 2 = SVID_ALERT0_CPU1_R_N
R3B2  RES  49.9 1% CHIP  pkg 0402  page 55 : 1 = SVID_ALERT0_CPU1_R_N ; 2 = PVCCIO_CPU1
R3B3  RES  0.0 5% CHIP  pkg 0402  page 55 : 1 = SVID_DIO0_CPU1 ; 2 = SVID_DIO0_CPU1_R
R3B4  RES  100.0 1% CHIP  pkg 0402  page 55 : 1 = SVID_DIO0_CPU1_R ; 2 = PVCCIO_CPU1
R3B5  RES  0.0 5% CHIP  pkg 0402  page 55 : 1 = SVID_CLK0_CPU1 ; 2 = SVID_CLK0_CPU1_R
R3D1  RES  90.9 1% CHIP  pkg 0402  page 55 : 1 = A_CPU1_KLM_RCOMP0 ; 2 = GND
R3D2  RES  90.9 1% CHIP  pkg 0402  page 55 : 1 = A_CPU1_KLM_RCOMP1 ; 2 = GND
R3D3  RES  100.0 1% CHIP  pkg 0402  page 55 : 1 = A_CPU1_KLM_RCOMP2 ; 2 = GND
R3D4  RES  49.9 1% CHIP  pkg 0402  page 55 : 1 = A_CPU1_MCP01_RBIAS ; 2 = GND
R3D9  RES  49.9 1% CHIP  pkg 0402  page 90 : 1 = PD_CPU1_TEST12 ; 2 = GND
R3D12  RES  240 1.0% EMPTY  pkg 0402  page 90 : 1 = GND ; 2 = PD_CPU1_TXT_PLTEN
R3D13  RES  240 1.0% EMPTY  pkg 0402  page 90 : 1 = GND ; 2 = PD_CPU1_BIST_ENABLE
R3D14  RES  2.2 1.0% CHIP  pkg 0603  page 102 : 1 = P3V3_DB1200 ; 2 = P3V3_DB1200_A
R3D15  RES  49.9 1% CHIP  pkg 0402  page 96 : 1 = PVCCIO_CPU1 ; 2 = PWRGD_CPU1_G
R3D16  RES  240 1.0% EMPTY  pkg 0402  page 90 : 1 = PVCCIO_CPU1 ; 2 = H_CPU1_BMCINIT
R3D17  RES  240 1.0% EMPTY  pkg 0402  page 90 : 1 = PVCCIO_CPU1 ; 2 = PU_CPU1_SOCKET_ID_1
R3D18  RES  0.0 5% CHIP  pkg 0402  page 97 : 1 = H_CPU0_FAST_WAKE_N ; 2 = H_CPU1_FAST_WAKE_N
R3D19  RES  49.9 1% CHIP  pkg 0402  page 55 : 1 = A_CPU1_UPI01_RBIAS ; 2 = GND
R3D20  RES  49.9 1% CHIP  pkg 0402  page 96 : 1 = PVCCIO_CPU1 ; 2 = RST_CPU1_G_N
R3D21  RES  64.9 1.0% CHIP  pkg 0402  page 96 : 1 = PVDDQ_GHJ ; 2 = PWRGD_CPU1_DRAMPWROK_GHJ_G
R3D22  RES  240 1.0% EMPTY  pkg 0402  page 90 : 1 = PVCCIO_CPU1 ; 2 = PU_CPU1_FRMAGENT
R3D23  RES  240 1.0% EMPTY  pkg 0402  page 90 : 1 = PVCCIO_CPU1 ; 2 = PU_CPU1_TXT_AGENT
R3D24  RES  240 1.0% CHIP  pkg 0402  page 90 : 1 = PVCCIO_CPU1 ; 2 = PU_CPU1_SOCKET_ID_0
R3D25  RES  240 1.0% EMPTY  pkg 0402  page 90 : 1 = GND ; 2 = PD_CPU1_EAR_N
R3D26  RES  240 1.0% EMPTY  pkg 0402  page 90 : 1 = PVCCIO_CPU1 ; 2 = PU_CPU1_SAFE_MODE_BOOT
R3D27  RES  249 0.1% CHIP  pkg 0402  page 71 : 1 = VSENSE_PMAX_CPU1 ; 2 = GND
R3D28  RES  100.0 1% CHIP  pkg 0402  page 214 : 1 = VSENSE_PVCCIO_CPU1_AVSN ; 2 = GND
R3D31  RES  0.0 5% EMPTY  pkg 0402  page 156 : 1 = FM_CPU_BMC_INIT ; 2 = H_CPU1_BMCINIT
R3D32  RES  10.0 1% EMPTY  pkg 0402  page 71 : 1 = PVCCIO_CPU1 ; 2 = VSENSE_PMAX_CPU1
R3E1  RES  100.0 1% CHIP  pkg 0402  page 214 : 1 = VSENSE_PVCCIO_CPU1_AVSP ; 2 = PVCCIO_CPU1
R3F1  RES  0.0 5% EMPTY  pkg 0402  page 104 : 1 = CLK_322M_156M_CPU1_OSC_VRM_DN ; 2 = CLK_156M_OSC_CPU1_HFI_DN
R3F2  RES  0.0 5% CHIP  pkg 0402  page 104 : 1 = CLK_156M_OSC_BRD_CPU1_DN ; 2 = CLK_156M_OSC_CPU1_HFI_DN
R3F3  RES  0.0 5% EMPTY  pkg 0402  page 104 : 1 = CLK_322M_156M_CPU1_OSC_VRM_DP ; 2 = CLK_156M_OSC_CPU1_HFI_DP
R3F4  RES  0.0 5% CHIP  pkg 0402  page 104 : 1 = CLK_156M_OSC_BRD_CPU1_DP ; 2 = CLK_156M_OSC_CPU1_HFI_DP
R3F5  RES  0.0 5% EMPTY  pkg 0402  page 104 : 1 = CLK_322M_156M_CPU1_OSC_VRM_DN ; 2 = CLK_322M_OSC_CPU1_RC_DN
R3F6  RES  0.0 5% EMPTY  pkg 0402  page 104 : 1 = CLK_322M_156M_CPU1_OSC_VRM_DP ; 2 = CLK_322M_OSC_CPU1_RC_DP
R3L1  RES  0.0 5% CHIP  pkg 0402  page 236 : 1 = VR_PVNN_PCH_PH1_VCIN ; 2 = P5V_STBY
R3L4  RES  0.0 5% CHIP  pkg 0402  page 236 : 1 = VR_P1V05_PCH_STBY_PH1_VCIN ; 2 = P5V_STBY
R3L6  RES  0.0 5% CHIP  pkg 0402  page 219 : 1 = VR_PVDDQ_DEF_PH1_VCIN ; 2 = P5V_STBY
R3L8  RES  0.0 5% CHIP  pkg 0402  page 219 : 1 = VR_PVDDQ_DEF_PH2_VCIN ; 2 = P5V_STBY
R3L11  RES  100.0 1% EMPTY  pkg 0402  page 218 : 1 = PVCCIO_CPU0 ; 2 = SVID_DIO1_CPU0_R
R3L13  RES  49.9 1% EMPTY  pkg 0402  page 218 : 1 = PVCCIO_CPU0 ; 2 = SVID_CLK1_CPU0_R
R3L14  RES  68.1K 1% EMPTY  pkg 0402  page 236 : 1 = VR_P1V05_PCH_STBY_OCSET ; 2 = GND
R3L15  RES  68.1K 1% EMPTY  pkg 0402  page 236 : 1 = VR_PVNN_PCH_STBY_OCSET ; 2 = GND
R3M1  RES  0.0 5% CHIP  pkg 0402  page 218 : 1 = P3V3_STBY ; 2 = VR_PVDDQ_DEF_VDD
R3M3  RES  22.1 1.0% CHIP  pkg 0402  page 218 : 1 = PWRGD_PVDDQ_DEF_R ; 2 = PWRGD_PVDDQ_DEF
R3M5  RES  100.0K 1% EMPTY  pkg 0402  page 218 : 1 = P3V3_STBY ; 2 = VR_PVDDQ_DEF_VREN
R3M6  RES  0.0 5% CHIP  pkg 0402  page 218 : 1 = FM_PVDDQ_DEF_EN ; 2 = VR_PVDDQ_DEF_VREN
R3M8  RES  100.0K 1% CHIP  pkg 0402  page 116 : 1 = P2E_SSB_BMC_RX_C_DP ; 2 = GND
R3M9  RES  100.0K 1% CHIP  pkg 0402  page 116 : 1 = P2E_SSB_BMC_RX_C_DN ; 2 = GND
R3M10  RES  1.00K 1% CHIP  pkg 0402  page 112 : 1 = XDP_PCH_CPU_TCK0 ; 2 = GND
R3M11  RES  100.0 1% CHIP  pkg 0402  page 116 : 1 = A_PCIE_RCOMP_P ; 2 = A_PCIE_RCOMP_N
R3M12  RES  100.0 1% CHIP  pkg 0402  page 116 : 1 = A_PCIEUP_RCOMP_P ; 2 = A_PCIEUP_RCOMP_N
R3N1  RES  169 1.0% CHIP  pkg 0402  page 114 : 1 = A_PCH_XCLK_BIASREF ; 2 = GND
R3N2  RES  4.75K 1% EMPTY  pkg 0402  page 125 : 1 = P3V3_STBY ; 2 = FM_FLASH_DESC_OVERRIDE
R3N3  RES  2.0K 1% CHIP  pkg 0402  page 133 : 1 = GND ; 2 = PWRGD_PCH_PWROK
R3N4  RES  20.0K 1% CHIP  pkg 0402  page 137 : 1 = P3V3_RTC_STBY ; 2 = RST_SRTCRST_N
R3N7  RES  0.0 5% CHIP  pkg 0402  page 212 : 1 = VR_PVCCIO_CPU0_PH1_VCIN ; 2 = P5V_STBY
R3N9  RES  10.0 1% CHIP  pkg 0402  page 118 : 1 = H_PM_SYNC1_GTL_R ; 2 = H_PM_SYNC_GTL
R3N10  RES  10.0K 1% CHIP  pkg 0402  page 121 : 1 = P3V3_STBY ; 2 = FM_INTRUDER_HDR_PCH_N
R3N11  RES  4.75K 1% CHIP  pkg 0402  page 157 : 1 = P3V3_STBY ; 2 = FM_MP_PS_REDUNDANT_LOST_N
R3N12  RES  4.75K 1% CHIP  pkg 0402  page 157 : 1 = P3V3_STBY ; 2 = FM_MP_PS_FAIL_N
R3N13  RES  4.75K 1% CHIP  pkg 0402  page 118 : 1 = P3V3_STBY ; 2 = IRQ_LVC3_WAKE_N
R3N14  RES  49.9 1% EMPTY  pkg 0402  page 118 : 1 = H_PM_SYNC_GTL ; 2 = GND
R3N15  RES  1.00K 1% EMPTY  pkg 0402  page 133 : 1 = P1V05_PCH_STBY ; 2 = FM_PRSNT_2_4_N
R3N16  RES  1.00K 1% EMPTY  pkg 0402  page 133 : 1 = P1V05_PCH_STBY ; 2 = FM_PRSNT_2_5_N
R3N17  RES  1.00K 1% EMPTY  pkg 0402  page 125 : 1 = P3V3_STBY ; 2 = SPI_PCH_IO3
R3N19  RES  10.0 1% CHIP  pkg 0402  page 211 : 1 = VSENSE_PVCCIO_CPU0_AVSP ; 2 = VR_PVCCIO_CPU0_AVSP
R3N20  RES  100.0 1% CHIP  pkg 0402  page 212 : 1 = VSENSE_PVCCIO_CPU0_AVSN ; 2 = GND
R3N21  RES  100.0 1% CHIP  pkg 0402  page 212 : 1 = VSENSE_PVCCIO_CPU0_AVSP ; 2 = PVCCIO_CPU0
R3N22  RES  4.02K 1% CHIP  pkg 0402  page 211 : 1 = VR_PVCCIO_CPU0_XADDR2 ; 2 = GND
R3N23  RES  2.26K 1.0% EMPTY  pkg 0402  page 211 : 1 = P3V3_STBY ; 2 = PU_VR_PVCCIO_CPU0_FAULT1
R3N24  RES  33.2 1% CHIP  pkg 0402  page 146 : 1 = LPC_LAD2_IO2 ; 2 = LPC_LAD2_IO2_R
R3N26  RES  33.2 1% CHIP  pkg 0402  page 146 : 1 = LPC_LAD0_IO0 ; 2 = LPC_LAD0_IO0_R
R3N29  RES  16K 1.0% CHIP  pkg 0402  page 194 : 1 = VR_PVCCIOMCP_CPU0_XADDR1 ; 2 = GND
R3N30  RES  0.0 5% EMPTY  pkg 0402  page 152 : 1 = H_CPU0_MEMABC_MEMHOT_LVT3_N ; 2 = H_CPU0_MEMABC_MEMHOT_PCH_N
R3N31  RES  3.16K 1% CHIP  pkg 0402  page 211 : 1 = VR_PVCCIO_CPU0_XADDR1 ; 2 = GND
R3P1  RES  0.0 5% CHIP  pkg 0402  page 211 : 1 = SVID_ALERT_PVCCIO_CPU0 ; 2 = SVID_ALERT0_CPU0_R_N
R3P2  RES  0.0 5% CHIP  pkg 0402  page 121 : 1 = RMII_BMC_PCH_SPRNGVLLE_CRSDV ; 2 = RMII_BMC_PCH_SPRNGVLLE_CRSDV_R1
R3P3  RES  0.0 5% CHIP  pkg 0402  page 121 : 1 = RMII_SPRNGVLLE_BMC_PCH_RXD0 ; 2 = RMII_SPRNGVLLE_BMC_PCH_RXD0_R1
R3P5  RES  1.00K 1% EMPTY  pkg 0402  page 133 : 1 = P1V05_PCH_STBY ; 2 = FM_PRSNT_2_2_N
R3P6  RES  1.00K 1% EMPTY  pkg 0402  page 133 : 1 = P1V05_PCH_STBY ; 2 = FM_PRSNT_2_3_N
